# S9S_MB_2U (Grand Teton) — schematic netlist excerpt (pin names and nets, part order shuffled) for the footprints in the layout excerpt that follows; sources: Cadence DE-HDL packaged netlist, KiCad conversion of 03242023_DA0F0TMBIJ0_F0T_Motherboard_J_brd_V01_OCP.brd

PC475  Q_CAP  470PF 50V 10% X7R  pkg 0402  page 292 : A = PVCCINFAON_CPU1_ATSEN ; B = GND
D81  Q_LED  IC  pkg SMLF  page 254 : A = LED_PWRGD_PVPP_HBM_CPU1 ; C = LED_PWRGD_PVPP_HBM_CPU1_D

(kicad_pcb
	(version 20260206)
	(generator "pcbnew")
	(generator_version "10.0")
	(general
		(thickness 1.6)
		(legacy_teardrops no)
	)
	(paper "A4")
	(title_block
		(title "03242023_DA0F0TMBIJ0_F0T_Motherboard_J_brd_V01_OCP.brd")
		(comment 1 "Grand Teton / footprints 3060-3061 of 6105")
	)
	(layers
		(0 "F.Cu" signal "TOP")
		(4 "In1.Cu" signal "GND")
		(6 "In2.Cu" signal "IN1")
		(8 "In3.Cu" signal "GND1")
		(10 "In4.Cu" signal "IN2")
		(12 "In5.Cu" signal "GND2")
		(14 "In6.Cu" signal "IN3")
		(16 "In7.Cu" signal "GND3")
		(18 "In8.Cu" signal "VCC")
		(20 "In9.Cu" signal "VCC1")
		(22 "In10.Cu" signal "GND4")
		(24 "In11.Cu" signal "IN4")
		(26 "In12.Cu" signal "GND5")
		(28 "In13.Cu" signal "IN5")
		(30 "In14.Cu" signal "GND6")
		(32 "In15.Cu" signal "IN6")
		(34 "In16.Cu" signal "GND7")
		(2 "B.Cu" signal "BOTTOM")
		(9 "F.Adhes" user "F.Adhesive")
		(11 "B.Adhes" user "B.Adhesive")
		(13 "F.Paste" user "Package Geometry/Pastemask Top")
		(15 "B.Paste" user "Package Geometry/Pastemask Bottom")
		(5 "F.SilkS" user "Ref Des/Silkscreen Top")
		(7 "B.SilkS" user "Ref Des/Silkscreen Bottom")
		(1 "F.Mask" user "Board Geometry/Soldermask Top")
		(3 "B.Mask" user "Board Geometry/Soldermask Bottom")
		(17 "Dwgs.User" user "User.Drawings")
		(19 "Cmts.User" user "User.Comments")
		(21 "Eco1.User" user "User.Eco1")
		(23 "Eco2.User" user "User.Eco2")
		(25 "Edge.Cuts" user "Board Geometry/Outline")
		(27 "Margin" user)
		(31 "F.CrtYd" user "Package Geometry/Place Bound Top")
		(29 "B.CrtYd" user "Package Geometry/Place Bound Bottom")
		(35 "F.Fab" user "Ref Des/Assembly Top")
		(33 "B.Fab" user "Ref Des/Assembly Bottom")
	)
	(footprint ""
		(layer "F.Cu")
		(at 74.395076 -79.078836)
		(property "Reference" "D81"
			(at -38.71341 34.331402 90)
			(unlocked yes)
			(layer "F.SilkS")
			(effects
				(font
					(size 0.635 0.4064)
					(thickness 0.1524)
				)
				(justify left)
			)
		)
		(property "Value" ""
			(at 0 0 0)
			(layer "F.Fab")
			(effects
				(font
					(size 1.27 1.27)
				)
			)
		)
		(duplicate_pad_numbers_are_jumpers no)
		(fp_line
			(start -0.90678 0.4826)
			(end -0.90678 -0.4699)
			(stroke
				(width 0.1524)
				(type default)
			)
			(layer "F.SilkS")
		)
		(fp_line
			(start -0.89408 -0.4826)
			(end 0.90678 -0.4826)
			(stroke
				(width 0.1524)
				(type default)
			)
			(layer "F.SilkS")
		)
		(fp_line
			(start -0.79248 -0.4826)
			(end 1.03378 -0.4826)
			(stroke
				(width 0.1524)
				(type default)
			)
			(layer "F.SilkS")
		)
		(fp_line
			(start -0.64008 -0.4826)
			(end 1.16078 -0.4826)
			(stroke
				(width 0.1524)
				(type default)
			)
			(layer "F.SilkS")
		)
		(fp_line
			(start 0.90678 -0.4826)
			(end 0.90678 0.4826)
			(stroke
				(width 0.1524)
				(type default)
			)
			(layer "F.SilkS")
		)
		(fp_line
			(start 0.90678 0.4826)
			(end -0.90678 0.4826)
			(stroke
				(width 0.1524)
				(type default)
			)
			(layer "F.SilkS")
		)
		(fp_line
			(start 1.03378 -0.4826)
			(end 1.03378 0.4826)
			(stroke
				(width 0.1524)
				(type default)
			)
			(layer "F.SilkS")
		)
		(fp_line
			(start 1.03378 0.4826)
			(end -0.79248 0.4826)
			(stroke
				(width 0.1524)
				(type default)
			)
			(layer "F.SilkS")
		)
		(fp_line
			(start 1.16078 -0.4826)
			(end 1.16078 0.4826)
			(stroke
				(width 0.1524)
				(type default)
			)
			(layer "F.SilkS")
		)
		(fp_line
			(start 1.16078 0.4826)
			(end -0.64008 0.4826)
			(stroke
				(width 0.1524)
				(type default)
			)
			(layer "F.SilkS")
		)
		(fp_line
			(start -0.499872 -0.249936)
			(end 0.499872 -0.249936)
			(stroke
				(width 0.1)
				(type default)
			)
			(layer "F.Fab")
		)
		(fp_line
			(start -0.499872 0.249936)
			(end -0.499872 -0.249936)
			(stroke
				(width 0.1)
				(type default)
			)
			(layer "F.Fab")
		)
		(fp_line
			(start 0.499872 -0.249936)
			(end 0.499872 0.249936)
			(stroke
				(width 0.1)
				(type default)
			)
			(layer "F.Fab")
		)
		(fp_line
			(start 0.499872 0.249936)
			(end -0.499872 0.249936)
			(stroke
				(width 0.1)
				(type default)
			)
			(layer "F.Fab")
		)
		(pad "A" smd rect
			(at -0.47498 0)
			(size 0.6096 0.7112)
			(layers "F.Cu" "F.Mask" "F.Paste")
			(net "LED_PWRGD_PVPP_HBM_CPU1")
		)
		(pad "C" smd rect
			(at 0.47498 0)
			(size 0.6096 0.7112)
			(layers "F.Cu" "F.Mask" "F.Paste")
			(net "LED_PWRGD_PVPP_HBM_CPU1_D")
		)
	)
	(footprint ""
		(layer "F.Cu")
		(at 27.0383 -130.396996 180)
		(property "Reference" "PC475"
			(at 0 0 180)
			(layer "F.SilkS")
			(hide yes)
			(effects
				(font
					(size 1.27 1.27)
				)
			)
		)
		(property "Value" ""
			(at 0 0 180)
			(layer "F.Fab")
			(effects
				(font
					(size 1.27 1.27)
				)
			)
		)
		(duplicate_pad_numbers_are_jumpers no)
		(fp_line
			(start 0.7874 0.4064)
			(end -0.7874 0.4064)
			(stroke
				(width 0.1524)
				(type default)
			)
			(layer "F.SilkS")
		)
		(fp_line
			(start 0.7874 -0.4064)
			(end 0.7874 0.4064)
			(stroke
				(width 0.1524)
				(type default)
			)
			(layer "F.SilkS")
		)
		(fp_line
			(start -0.7874 0.4064)
			(end -0.7874 -0.4064)
			(stroke
				(width 0.1524)
				(type default)
			)
			(layer "F.SilkS")
		)
		(fp_line
			(start -0.7874 -0.4064)
			(end 0.7874 -0.4064)
			(stroke
				(width 0.1524)
				(type default)
			)
			(layer "F.SilkS")
		)
		(fp_line
			(start 0.67945 0.3048)
			(end 0.120396 0.3048)
			(stroke
				(width 0.1)
				(type default)
			)
			(layer "F.Fab")
		)
		(fp_line
			(start 0.67945 -0.3048)
			(end 0.67945 0.3048)
			(stroke
				(width 0.1)
				(type default)
			)
			(layer "F.Fab")
		)
		(fp_line
			(start 0.12065 -0.2794)
			(end 0.12065 -0.3048)
			(stroke
				(width 0.1)
				(type default)
			)
			(layer "F.Fab")
		)
		(fp_line
			(start 0.12065 -0.3048)
			(end 0.67945 -0.3048)
			(stroke
				(width 0.1)
				(type default)
			)
			(layer "F.Fab")
		)
		(fp_line
			(start 0.120396 0.3048)
			(end 0.120396 0.2794)
			(stroke
				(width 0.1)
				(type default)
			)
			(layer "F.Fab")
		)
		(fp_line
			(start 0.120396 0.2794)
			(end -0.12065 0.2794)
			(stroke
				(width 0.1)
				(type default)
			)
			(layer "F.Fab")
		)
		(fp_line
			(start -0.12065 0.3048)
			(end -0.67945 0.3048)
			(stroke
				(width 0.1)
				(type default)
			)
			(layer "F.Fab")
		)
		(fp_line
			(start -0.12065 0.2794)
			(end -0.12065 0.3048)
			(stroke
				(width 0.1)
				(type default)
			)
			(layer "F.Fab")
		)
		(fp_line
			(start -0.12065 -0.2794)
			(end 0.12065 -0.2794)
			(stroke
				(width 0.1)
				(type default)
			)
			(layer "F.Fab")
		)
		(fp_line
			(start -0.12065 -0.305054)
			(end -0.12065 -0.2794)
			(stroke
				(width 0.1)
				(type default)
			)
			(layer "F.Fab")
		)
		(fp_line
			(start -0.67945 0.3048)
			(end -0.67945 -0.305054)
			(stroke
				(width 0.1)
				(type default)
			)
			(layer "F.Fab")
		)
		(fp_line
			(start -0.67945 -0.305054)
			(end -0.12065 -0.305054)
			(stroke
				(width 0.1)
				(type default)
			)
			(layer "F.Fab")
		)
		(pad "1" smd circle
			(at -0.40005 0 180)
			(size 0 0)
			(layers "F.Cu" "F.Mask" "F.Paste")
			(net "PVCCINFAON_CPU1_ATSEN")
		)
		(pad "2" smd circle
			(at 0.40005 0 180)
			(size 0 0)
			(layers "F.Cu" "F.Mask" "F.Paste")
			(net "GND")
		)
	)
)
